(kicad_pcb
	(version 20260206)
	(generator "pcbnew")
	(generator_version "10.0")
	(general
		(thickness 1.6)
		(legacy_teardrops no)
	)
	(paper "A4")
	(title_block
		(title "Bryce Canyon_R.DPB_16317-1_OCP.brd")
		(comment 1 "Bryce Canyon / footprints 251-258 of 2099")
	)
	(layers
		(0 "F.Cu" signal "TOP")
		(4 "In1.Cu" signal "L2GND")
		(6 "In2.Cu" signal "L3")
		(8 "In3.Cu" signal "L4VCC")
		(10 "In4.Cu" signal "L5VCC")
		(12 "In5.Cu" signal "L6")
		(14 "In6.Cu" signal "L7GND")
		(2 "B.Cu" signal "BOTTOM")
		(9 "F.Adhes" user "F.Adhesive")
		(11 "B.Adhes" user "B.Adhesive")
		(13 "F.Paste" user "Package Geometry/Pastemask Top")
		(15 "B.Paste" user "Package Geometry/Pastemask Bottom")
		(5 "F.SilkS" user "Ref Des/Silkscreen Top")
		(7 "B.SilkS" user "Ref Des/Silkscreen Bottom")
		(1 "F.Mask" user "Board Geometry/Soldermask Top")
		(3 "B.Mask" user "Board Geometry/Soldermask Bottom")
		(17 "Dwgs.User" user "User.Drawings")
		(19 "Cmts.User" user "User.Comments")
		(21 "Eco1.User" user "User.Eco1")
		(23 "Eco2.User" user "User.Eco2")
		(25 "Edge.Cuts" user "Board Geometry/Outline")
		(27 "Margin" user)
		(31 "F.CrtYd" user "Package Geometry/Place Bound Top")
		(29 "B.CrtYd" user "Package Geometry/Place Bound Bottom")
		(35 "F.Fab" user "Ref Des/Assembly Top")
		(33 "B.Fab" user "Ref Des/Assembly Bottom")
	)
	(footprint ""
		(layer "F.Cu")
		(at 172.466 -150.622 -90)
		(property "Reference" "C254"
			(at 0 0 270)
			(layer "F.SilkS")
			(hide yes)
			(effects
				(font
					(size 1.27 1.27)
				)
			)
		)
		(property "Value" "SC4D7U25V5KX-1-GP"
			(at -0.0762 -6.1214 270)
			(unlocked yes)
			(layer "F.Fab")
			(hide yes)
			(effects
				(font
					(size 1.016 1.016)
					(thickness 0.1524)
				)
			)
		)
		(property "Device Type" "C805H58"
			(at -0.0762 -8.1534 270)
			(unlocked yes)
			(layer "F.Fab")
			(hide yes)
			(effects
				(font
					(size 1.016 1.016)
					(thickness 0.1524)
				)
			)
		)
		(duplicate_pad_numbers_are_jumpers no)
		(fp_line
			(start 0.635 0)
			(end -0.635 0)
			(stroke
				(width 0.508)
				(type default)
			)
			(layer "F.SilkS")
		)
		(fp_rect
			(start -0.9652 1.778)
			(end 0.9652 -1.778)
			(stroke
				(width 0)
				(type default)
			)
			(fill no)
			(layer "F.CrtYd")
		)
		(fp_poly
			(pts
				(xy -0.9652 -1.778) (xy 0.9652 -1.778) (xy 0.9652 1.778) (xy -0.9652 1.778)
			)
			(stroke
				(width 0)
				(type default)
			)
			(fill no)
			(layer "F.Fab")
		)
		(pad "1" smd rect
			(at 0 -0.9652 270)
			(size 1.397 1.143)
			(layers "F.Cu" "F.Mask" "F.Paste")
			(net "P12V_HDD17")
		)
		(pad "2" smd rect
			(at 0 0.9652 270)
			(size 1.397 1.143)
			(layers "F.Cu" "F.Mask" "F.Paste")
			(net "GND")
		)
	)
	(footprint ""
		(layer "F.Cu")
		(at 394.589 -274.955 180)
		(property "Reference" "C138"
			(at 0 0 180)
			(layer "F.SilkS")
			(hide yes)
			(effects
				(font
					(size 1.27 1.27)
				)
			)
		)
		(property "Value" "SC4D7U25V5KX-1-GP"
			(at -0.0762 -6.1214 180)
			(unlocked yes)
			(layer "F.Fab")
			(hide yes)
			(effects
				(font
					(size 1.016 1.016)
					(thickness 0.1524)
				)
			)
		)
		(property "Device Type" "C805H58"
			(at -0.0762 -8.1534 180)
			(unlocked yes)
			(layer "F.Fab")
			(hide yes)
			(effects
				(font
					(size 1.016 1.016)
					(thickness 0.1524)
				)
			)
		)
		(duplicate_pad_numbers_are_jumpers no)
		(fp_line
			(start 0.635 0)
			(end -0.635 0)
			(stroke
				(width 0.508)
				(type default)
			)
			(layer "F.SilkS")
		)
		(fp_rect
			(start -0.9652 1.778)
			(end 0.9652 -1.778)
			(stroke
				(width 0)
				(type default)
			)
			(fill no)
			(layer "F.CrtYd")
		)
		(fp_poly
			(pts
				(xy -0.9652 -1.778) (xy 0.9652 -1.778) (xy 0.9652 1.778) (xy -0.9652 1.778)
			)
			(stroke
				(width 0)
				(type default)
			)
			(fill no)
			(layer "F.Fab")
		)
		(pad "1" smd rect
			(at 0 -0.9652 180)
			(size 1.397 1.143)
			(layers "F.Cu" "F.Mask" "F.Paste")
			(net "P12V_HDD8")
		)
		(pad "2" smd rect
			(at 0 0.9652 180)
			(size 1.397 1.143)
			(layers "F.Cu" "F.Mask" "F.Paste")
			(net "GND")
		)
	)
	(footprint ""
		(layer "F.Cu")
		(at 190.258954 -133.75005 -90)
		(property "Reference" "VIA36"
			(at 0 0 270)
			(layer "F.SilkS")
			(hide yes)
			(effects
				(font
					(size 1.27 1.27)
				)
			)
		)
		(property "Value" "100OHM-8L-2D36MM-L16-GP"
			(at -3.4036 -0.4572 270)
			(unlocked yes)
			(layer "F.Fab")
			(hide yes)
			(effects
				(font
					(size 1.016 1.016)
					(thickness 0.1524)
				)
			)
		)
		(property "Device Type" "VIA-PCIE-4P-427097"
			(at -3.4036 -1.9812 270)
			(unlocked yes)
			(layer "F.Fab")
			(hide yes)
			(effects
				(font
					(size 1.016 1.016)
					(thickness 0.1524)
				)
			)
		)
		(duplicate_pad_numbers_are_jumpers no)
		(fp_rect
			(start -2.1336 0.4826)
			(end 2.1336 -0.4826)
			(stroke
				(width 0)
				(type default)
			)
			(fill no)
			(layer "F.CrtYd")
		)
		(fp_rect
			(start -2.1336 0.4826)
			(end 2.1336 -0.4826)
			(stroke
				(width 0)
				(type default)
			)
			(fill no)
			(layer "F.Fab")
		)
		(pad "1" thru_hole circle
			(at -1.651 0 270)
			(size 0.508 0.508)
			(drill 0.254)
			(layers "*.Cu" "*.Mask")
			(remove_unused_layers no)
			(net "GND")
			(clearance 0.2286)
			(thermal_gap 0.2286)
		)
		(pad "2" thru_hole circle
			(at -0.635 0 270)
			(size 0.508 0.508)
			(drill 0.254)
			(layers "*.Cu" "*.Mask")
			(remove_unused_layers no)
			(net "PHY_DRV_B_TO_SCC_B_17_DP")
			(clearance 0.2286)
			(thermal_gap 0.2286)
		)
		(pad "3" thru_hole circle
			(at 0.635 0 270)
			(size 0.508 0.508)
			(drill 0.254)
			(layers "*.Cu" "*.Mask")
			(remove_unused_layers no)
			(net "PHY_DRV_B_TO_SCC_B_17_DN")
			(clearance 0.2286)
			(thermal_gap 0.2286)
		)
		(pad "4" thru_hole circle
			(at 1.651 0 270)
			(size 0.508 0.508)
			(drill 0.254)
			(layers "*.Cu" "*.Mask")
			(remove_unused_layers no)
			(net "GND")
			(clearance 0.2286)
			(thermal_gap 0.2286)
		)
	)
	(footprint ""
		(layer "F.Cu")
		(at 321.634612 -130.21945 -90)
		(property "Reference" "C262"
			(at 0 0 270)
			(layer "F.SilkS")
			(hide yes)
			(effects
				(font
					(size 1.27 1.27)
				)
			)
		)
		(property "Value" "SCD01U16V1KX-GP"
			(at -2.8321 -1.7399 270)
			(unlocked yes)
			(layer "F.Fab")
			(hide yes)
			(effects
				(font
					(size 1.016 1.016)
					(thickness 0.1524)
				)
			)
		)
		(property "Device Type" "C0201H13"
			(at -2.8321 -3.2639 270)
			(unlocked yes)
			(layer "F.Fab")
			(hide yes)
			(effects
				(font
					(size 1.016 1.016)
					(thickness 0.1524)
				)
			)
		)
		(duplicate_pad_numbers_are_jumpers no)
		(fp_rect
			(start -0.2794 0.6477)
			(end 0.2794 -0.6477)
			(stroke
				(width 0)
				(type default)
			)
			(fill no)
			(layer "F.CrtYd")
		)
		(fp_rect
			(start -0.2794 0.6477)
			(end 0.2794 -0.6477)
			(stroke
				(width 0)
				(type default)
			)
			(fill no)
			(layer "F.Fab")
		)
		(pad "1" smd custom
			(at 0 -0.2794 270)
			(size 0.0762 0.0762)
			(layers "F.Cu" "F.Mask" "F.Paste")
			(net "SAS_HDD_RX_N18")
			(options
				(clearance outline)
				(anchor circle)
			)
			(primitives
				(gr_poly
					(pts
						(arc
							(start 0.1524 -0.127)
							(mid 0.137521 -0.162921)
							(end 0.1016 -0.1778)
						)
						(arc
							(start -0.1016 -0.1778)
							(mid -0.137521 -0.162921)
							(end -0.1524 -0.127)
						)
						(arc
							(start -0.1524 0.127)
							(mid -0.137521 0.162921)
							(end -0.1016 0.1778)
						)
						(arc
							(start 0.1016 0.1778)
							(mid 0.137521 0.162921)
							(end 0.1524 0.127)
						)
					)
					(width 0)
					(fill yes)
				)
			)
		)
		(pad "2" smd custom
			(at 0 0.2794 270)
			(size 0.0762 0.0762)
			(layers "F.Cu" "F.Mask" "F.Paste")
			(net "PHY_SCC_B_TO_DRV_B_18_DN")
			(options
				(clearance outline)
				(anchor circle)
			)
			(primitives
				(gr_poly
					(pts
						(arc
							(start 0.1524 -0.127)
							(mid 0.137521 -0.162921)
							(end 0.1016 -0.1778)
						)
						(arc
							(start -0.1016 -0.1778)
							(mid -0.137521 -0.162921)
							(end -0.1524 -0.127)
						)
						(arc
							(start -0.1524 0.127)
							(mid -0.137521 0.162921)
							(end -0.1016 0.1778)
						)
						(arc
							(start 0.1016 0.1778)
							(mid 0.137521 0.162921)
							(end 0.1524 0.127)
						)
					)
					(width 0)
					(fill yes)
				)
			)
		)
	)
	(footprint ""
		(layer "F.Cu")
		(at 449.5165 -132.437124)
		(property "Reference" "VIA46"
			(at 0 0 0)
			(layer "F.SilkS")
			(hide yes)
			(effects
				(font
					(size 1.27 1.27)
				)
			)
		)
		(property "Value" "100OHM-8L-2D36MM-L16-GP"
			(at -3.4036 -0.4572 0)
			(unlocked yes)
			(layer "F.Fab")
			(hide yes)
			(effects
				(font
					(size 1.016 1.016)
					(thickness 0.1524)
				)
			)
		)
		(property "Device Type" "VIA-PCIE-4P-427097"
			(at -3.4036 -1.9812 0)
			(unlocked yes)
			(layer "F.Fab")
			(hide yes)
			(effects
				(font
					(size 1.016 1.016)
					(thickness 0.1524)
				)
			)
		)
		(duplicate_pad_numbers_are_jumpers no)
		(fp_rect
			(start -2.1336 0.4826)
			(end 2.1336 -0.4826)
			(stroke
				(width 0)
				(type default)
			)
			(fill no)
			(layer "F.CrtYd")
		)
		(fp_rect
			(start -2.1336 0.4826)
			(end 2.1336 -0.4826)
			(stroke
				(width 0)
				(type default)
			)
			(fill no)
			(layer "F.Fab")
		)
		(pad "1" thru_hole circle
			(at -1.651 0)
			(size 0.508 0.508)
			(drill 0.254)
			(layers "*.Cu" "*.Mask")
			(remove_unused_layers no)
			(net "GND")
			(clearance 0.2286)
			(thermal_gap 0.2286)
		)
		(pad "2" thru_hole circle
			(at -0.635 0)
			(size 0.508 0.508)
			(drill 0.254)
			(layers "*.Cu" "*.Mask")
			(remove_unused_layers no)
			(net "PHY_DRV_B_TO_SCC_B_22_DP")
			(clearance 0.2286)
			(thermal_gap 0.2286)
		)
		(pad "3" thru_hole circle
			(at 0.635 0)
			(size 0.508 0.508)
			(drill 0.254)
			(layers "*.Cu" "*.Mask")
			(remove_unused_layers no)
			(net "PHY_DRV_B_TO_SCC_B_22_DN")
			(clearance 0.2286)
			(thermal_gap 0.2286)
		)
		(pad "4" thru_hole circle
			(at 1.651 0)
			(size 0.508 0.508)
			(drill 0.254)
			(layers "*.Cu" "*.Mask")
			(remove_unused_layers no)
			(net "GND")
			(clearance 0.2286)
			(thermal_gap 0.2286)
		)
	)
	(footprint ""
		(layer "F.Cu")
		(at 473.202 -131.826 90)
		(property "Reference" "Q113"
			(at 0 0 90)
			(layer "F.SilkS")
			(hide yes)
			(effects
				(font
					(size 1.27 1.27)
				)
			)
		)
		(property "Value" "2N7002KDW-GP"
			(at -2.3622 -8.2042 90)
			(unlocked yes)
			(layer "F.Fab")
			(hide yes)
			(effects
				(font
					(size 1.016 1.016)
					(thickness 0.1524)
				)
			)
		)
		(property "Device Type" "SOT-363H44"
			(at -2.3622 -10.1092 90)
			(unlocked yes)
			(layer "F.Fab")
			(hide yes)
			(effects
				(font
					(size 1.016 1.016)
					(thickness 0.1524)
				)
			)
		)
		(duplicate_pad_numbers_are_jumpers no)
		(fp_line
			(start 1.4478 -1.7018)
			(end -1.4478 -1.7018)
			(stroke
				(width 0.1524)
				(type default)
			)
			(layer "F.SilkS")
		)
		(fp_line
			(start -1.4478 -1.7018)
			(end -1.4478 1.7018)
			(stroke
				(width 0.1524)
				(type default)
			)
			(layer "F.SilkS")
		)
		(fp_line
			(start -1.27 1.524)
			(end -1.27 0.6604)
			(stroke
				(width 0.4826)
				(type default)
			)
			(layer "F.SilkS")
		)
		(fp_line
			(start 1.4478 1.7018)
			(end 1.4478 -1.7018)
			(stroke
				(width 0.1524)
				(type default)
			)
			(layer "F.SilkS")
		)
		(fp_line
			(start -1.4478 1.7018)
			(end 1.4478 1.7018)
			(stroke
				(width 0.1524)
				(type default)
			)
			(layer "F.SilkS")
		)
		(fp_poly
			(pts
				(xy -1.524 -1.778) (xy 1.524 -1.778) (xy 1.524 1.778) (xy -1.524 1.778)
			)
			(stroke
				(width 0)
				(type default)
			)
			(fill no)
			(layer "F.CrtYd")
		)
		(fp_poly
			(pts
				(xy -1.524 -1.778) (xy 1.524 -1.778) (xy 1.524 1.778) (xy -1.524 1.778)
			)
			(stroke
				(width 0)
				(type default)
			)
			(fill no)
			(layer "F.Fab")
		)
		(pad "1" smd rect
			(at -0.65024 0.9398 90)
			(size 0.4064 1.016)
			(layers "F.Cu" "F.Mask" "F.Paste")
			(net "GND")
		)
		(pad "2" smd rect
			(at 0 0.9398 90)
			(size 0.4064 1.016)
			(layers "F.Cu" "F.Mask" "F.Paste")
			(net "SW_PWR_R_HDD23")
		)
		(pad "3" smd rect
			(at 0.65024 0.9398 90)
			(size 0.4064 1.016)
			(layers "F.Cu" "F.Mask" "F.Paste")
			(net "SW_HDD_P23")
		)
		(pad "4" smd rect
			(at 0.65024 -0.9398 90)
			(size 0.4064 1.016)
			(layers "F.Cu" "F.Mask" "F.Paste")
			(net "GND")
		)
		(pad "5" smd rect
			(at 0 -0.9398 90)
			(size 0.4064 1.016)
			(layers "F.Cu" "F.Mask" "F.Paste")
			(net "SW_HDD_G23")
		)
		(pad "6" smd rect
			(at -0.65024 -0.9398 90)
			(size 0.4064 1.016)
			(layers "F.Cu" "F.Mask" "F.Paste")
			(net "SW_HDD_R23")
		)
	)
	(footprint ""
		(layer "F.Cu")
		(at 188.120528 -374.531636 -90)
		(property "Reference" "Q205"
			(at 0 0 270)
			(layer "F.SilkS")
			(hide yes)
			(effects
				(font
					(size 1.27 1.27)
				)
			)
		)
		(property "Value" "SSM6P39TU-GP"
			(at 0.0508 -11.5824 270)
			(unlocked yes)
			(layer "F.Fab")
			(hide yes)
			(effects
				(font
					(size 1.016 1.016)
					(thickness 0.1524)
				)
			)
		)
		(property "Device Type" "UMT6H30"
			(at 0.0508 -13.1572 270)
			(unlocked yes)
			(layer "F.Fab")
			(hide yes)
			(effects
				(font
					(size 1.016 1.016)
					(thickness 0.1524)
				)
			)
		)
		(duplicate_pad_numbers_are_jumpers no)
		(fp_line
			(start 1.524 0.36449)
			(end -1.27 0.36449)
			(stroke
				(width 0.1524)
				(type default)
			)
			(layer "F.SilkS")
		)
		(fp_line
			(start 1.09347 0)
			(end 1.45796 0.36449)
			(stroke
				(width 0.1524)
				(type default)
			)
			(layer "F.SilkS")
		)
		(fp_line
			(start -1.27 -0.36449)
			(end -1.27 0.36449)
			(stroke
				(width 0.1524)
				(type default)
			)
			(layer "F.SilkS")
		)
		(fp_line
			(start -1.27 -0.36449)
			(end 1.524 -0.36449)
			(stroke
				(width 0.1524)
				(type default)
			)
			(layer "F.SilkS")
		)
		(fp_line
			(start 1.45796 -0.36449)
			(end 1.09347 0)
			(stroke
				(width 0.1524)
				(type default)
			)
			(layer "F.SilkS")
		)
		(fp_line
			(start 1.524 -0.36449)
			(end 1.524 0.36449)
			(stroke
				(width 0.1524)
				(type default)
			)
			(layer "F.SilkS")
		)
		(fp_line
			(start 1.524 -0.36449)
			(end 1.45796 -0.36449)
			(stroke
				(width 0.1524)
				(type default)
			)
			(layer "F.SilkS")
		)
		(fp_line
			(start 1.524 -0.36449)
			(end 1.524 -1.82245)
			(stroke
				(width 0.508)
				(type default)
			)
			(layer "F.SilkS")
		)
		(fp_poly
			(pts
				(xy -0.65024 0.36449) (xy -0.65024 -0.36449) (xy 0.65024 -0.36449) (xy 0.65024 0.36449)
			)
			(stroke
				(width 0)
				(type default)
			)
			(fill yes)
			(layer "F.SilkS")
		)
		(fp_poly
			(pts
				(xy 1.016 -1.0668) (xy 1.016 1.0668) (xy -1.016 1.0668) (xy -1.016 -1.0668)
			)
			(stroke
				(width 0)
				(type default)
			)
			(fill no)
			(layer "F.CrtYd")
		)
		(fp_poly
			(pts
				(xy -1.524 1.905) (xy 1.524 1.905) (xy 1.524 -1.06426) (xy 1.016 -1.06426) (xy 1.016 1.0668) (xy -1.016 1.0668)
				(xy -1.016 -1.0668) (xy 1.524 -1.0668) (xy 1.524 -1.905) (xy -1.524 -1.905)
			)
			(stroke
				(width 0)
				(type default)
			)
			(fill no)
			(layer "F.CrtYd")
		)
		(fp_poly
			(pts
				(xy -1.524 -1.905) (xy -1.524 1.905) (xy 1.524 1.905) (xy 1.524 -1.905)
			)
			(stroke
				(width 0)
				(type default)
			)
			(fill no)
			(layer "F.Fab")
		)
		(pad "1" smd rect
			(at 0.65024 -1.02489 270)
			(size 0.4064 0.8128)
			(layers "F.Cu" "F.Mask" "F.Paste")
			(net "P12V_IN")
		)
		(pad "2" smd rect
			(at 0 -1.02489 270)
			(size 0.4064 0.8128)
			(layers "F.Cu" "F.Mask" "F.Paste")
			(net "FAN_YELLOW_LED1")
		)
		(pad "3" smd rect
			(at -0.65024 -1.02489 270)
			(size 0.4064 0.8128)
			(layers "F.Cu" "F.Mask" "F.Paste")
			(net "FAN_BLUE1")
		)
		(pad "4" smd rect
			(at -0.65024 1.02489 270)
			(size 0.4064 0.8128)
			(layers "F.Cu" "F.Mask" "F.Paste")
			(net "P12V_IN")
		)
		(pad "5" smd rect
			(at 0 1.02489 270)
			(size 0.4064 0.8128)
			(layers "F.Cu" "F.Mask" "F.Paste")
			(net "FAN_BLUE_LED1")
		)
		(pad "6" smd rect
			(at 0.65024 1.02489 270)
			(size 0.4064 0.8128)
			(layers "F.Cu" "F.Mask" "F.Paste")
			(net "FAN_YELLOW_1")
		)
	)
	(footprint ""
		(layer "F.Cu")
		(at 423.958004 -370.078 90)
		(property "Reference" "R956"
			(at 0 0 90)
			(layer "F.SilkS")
			(hide yes)
			(effects
				(font
					(size 1.27 1.27)
				)
			)
		)
		(property "Value" "27KR3F-GP"
			(at -0.0254 -2.5146 90)
			(unlocked yes)
			(layer "F.Fab")
			(hide yes)
			(effects
				(font
					(size 1.016 1.016)
					(thickness 0.1524)
				)
			)
		)
		(property "Device Type" "R603H22"
			(at -0.0254 -4.0386 90)
			(unlocked yes)
			(layer "F.Fab")
			(hide yes)
			(effects
				(font
					(size 1.016 1.016)
					(thickness 0.1524)
				)
			)
		)
		(duplicate_pad_numbers_are_jumpers no)
		(fp_line
			(start 0.2032 0)
			(end 0.4826 0)
			(stroke
				(width 0.2032)
				(type default)
			)
			(layer "F.SilkS")
		)
		(fp_line
			(start -0.4826 0)
			(end -0.2032 0)
			(stroke
				(width 0.2032)
				(type default)
			)
			(layer "F.SilkS")
		)
		(fp_rect
			(start -0.5842 1.3335)
			(end 0.5842 -1.3335)
			(stroke
				(width 0)
				(type default)
			)
			(fill no)
			(layer "F.CrtYd")
		)
		(fp_rect
			(start -0.5842 1.3335)
			(end 0.5842 -1.3335)
			(stroke
				(width 0)
				(type default)
			)
			(fill no)
			(layer "F.Fab")
		)
		(pad "1" smd custom
			(at 0 -0.762 90)
			(size 0.2159 0.2159)
			(layers "F.Cu" "F.Mask" "F.Paste")
			(net "FANTACH_R3")
			(options
				(clearance outline)
				(anchor circle)
			)
			(primitives
				(gr_poly
					(pts
						(arc
							(start -0.3302 -0.4318)
							(mid -0.402042 -0.402042)
							(end -0.4318 -0.3302)
						)
						(arc
							(start -0.4318 0.3302)
							(mid -0.402042 0.402042)
							(end -0.3302 0.4318)
						)
						(arc
							(start 0.3302 0.4318)
							(mid 0.402042 0.402042)
							(end 0.4318 0.3302)
						)
						(arc
							(start 0.4318 -0.3302)
							(mid 0.402042 -0.402042)
							(end 0.3302 -0.4318)
						)
					)
					(width 0)
					(fill yes)
				)
			)
		)
		(pad "2" smd custom
			(at 0 0.762 90)
			(size 0.2159 0.2159)
			(layers "F.Cu" "F.Mask" "F.Paste")
			(net "FAN_3_TACH0")
			(options
				(clearance outline)
				(anchor circle)
			)
			(primitives
				(gr_poly
					(pts
						(arc
							(start -0.3302 -0.4318)
							(mid -0.402042 -0.402042)
							(end -0.4318 -0.3302)
						)
						(arc
							(start -0.4318 0.3302)
							(mid -0.402042 0.402042)
							(end -0.3302 0.4318)
						)
						(arc
							(start 0.3302 0.4318)
							(mid 0.402042 0.402042)
							(end 0.4318 0.3302)
						)
						(arc
							(start 0.4318 -0.3302)
							(mid 0.402042 -0.402042)
							(end 0.3302 -0.4318)
						)
					)
					(width 0)
					(fill yes)
				)
			)
		)
	)
)
